(kicad_pcb
	(version 20241229)
	(generator "pcbnew")
	(generator_version "9.0")
	(general
		(thickness 1.711)
		(legacy_teardrops no)
	)
	(paper "A4")
	(title_block
		(title "Antmicro Baseboard for Jetson AGX Thor")
		(date "2026-02-18")
		(rev "1.1.0")
		(company "Antmicro Ltd")
		(comment 1 "www.antmicro.com")
		(comment 9 "footprints 744-747 of 1170")
	)
	(layers
		(0 "F.Cu" signal)
		(4 "In1.Cu" signal)
		(6 "In2.Cu" signal)
		(8 "In3.Cu" signal)
		(10 "In4.Cu" jumper)
		(12 "In5.Cu" signal)
		(14 "In6.Cu" signal)
		(16 "In7.Cu" signal)
		(18 "In8.Cu" signal)
		(2 "B.Cu" signal)
		(9 "F.Adhes" user "F.Adhesive")
		(11 "B.Adhes" user "B.Adhesive")
		(13 "F.Paste" user)
		(15 "B.Paste" user)
		(5 "F.SilkS" user "F.Silkscreen")
		(7 "B.SilkS" user "B.Silkscreen")
		(1 "F.Mask" user)
		(3 "B.Mask" user)
		(17 "Dwgs.User" user "User.Drawings")
		(19 "Cmts.User" user "User.Comments")
		(21 "Eco1.User" user "User.Eco1")
		(23 "Eco2.User" user "User.Eco2")
		(25 "Edge.Cuts" user)
		(27 "Margin" user)
		(31 "F.CrtYd" user "F.Courtyard")
		(29 "B.CrtYd" user "B.Courtyard")
		(35 "F.Fab" user)
		(33 "B.Fab" user)
	)
	(footprint "antmicro-footprints:R_0402_1005Metric"
		(layer "B.Cu")
		(at 182 57.5 -90)
		(descr "Resistor SMD 0402")
		(tags "resistor SMD 0402")
		(property "Reference" "R17"
			(at -3.55 -0.355 90)
			(layer "B.SilkS")
			(effects
				(font
					(size 0.7 0.7)
					(thickness 0.15)
				)
				(justify left bottom mirror)
			)
		)
		(property "Value" "R_2k2_0402"
			(at -1.011843 -1.772047 90)
			(layer "B.Fab")
			(effects
				(font
					(size 0.7 0.7)
					(thickness 0.15)
				)
				(justify left bottom mirror)
			)
		)
		(property "Datasheet" "https://www.bourns.com/docs/product-datasheets/cr.pdf"
			(at 0 0 90)
			(layer "B.Fab")
			(hide yes)
			(effects
				(font
					(size 1.27 1.27)
					(thickness 0.15)
				)
				(justify mirror)
			)
		)
		(property "Description" "SMD Chip Resistor, 2.2 kohm, ± 1%, 62.5 mW, 0402 [1005 Metric], Thick Film, General Purpose"
			(at 0 0 90)
			(layer "B.Fab")
			(hide yes)
			(effects
				(font
					(size 1.27 1.27)
					(thickness 0.15)
				)
				(justify mirror)
			)
		)
		(property "MPN" "CR0402-FX-2201GLF"
			(at 0 0 90)
			(unlocked yes)
			(layer "B.Fab")
			(hide yes)
			(effects
				(font
					(size 1 1)
					(thickness 0.15)
				)
				(justify mirror)
			)
		)
		(property "Manufacturer" "Bourns"
			(at 0 0 90)
			(unlocked yes)
			(layer "B.Fab")
			(hide yes)
			(effects
				(font
					(size 1 1)
					(thickness 0.15)
				)
				(justify mirror)
			)
		)
		(property "License" "Apache-2.0"
			(at 0 0 90)
			(unlocked yes)
			(layer "B.Fab")
			(hide yes)
			(effects
				(font
					(size 1 1)
					(thickness 0.15)
				)
				(justify mirror)
			)
		)
		(property "Author" "Antmicro"
			(at 0 0 90)
			(unlocked yes)
			(layer "B.Fab")
			(hide yes)
			(effects
				(font
					(size 1 1)
					(thickness 0.15)
				)
				(justify mirror)
			)
		)
		(property "Val" "2k2"
			(at 0 0 90)
			(unlocked yes)
			(layer "B.Fab")
			(hide yes)
			(effects
				(font
					(size 1 1)
					(thickness 0.15)
				)
				(justify mirror)
			)
		)
		(property "Tolerance" "1%"
			(at 0 0 90)
			(unlocked yes)
			(layer "B.Fab")
			(hide yes)
			(effects
				(font
					(size 1 1)
					(thickness 0.15)
				)
				(justify mirror)
			)
		)
		(sheetname "/Power/")
		(sheetfile "power.kicad_sch")
		(attr smd)
		(fp_rect
			(start -0.925 0.47)
			(end 0.925 -0.47)
			(stroke
				(width 0.05)
				(type default)
			)
			(fill no)
			(layer "B.CrtYd")
		)
		(fp_rect
			(start -0.5 0.25)
			(end 0.5 -0.25)
			(stroke
				(width 0.15)
				(type solid)
			)
			(fill no)
			(layer "B.Fab")
		)
		(fp_text user "${REFERENCE}"
			(at -0.95 -3.168 90)
			(layer "B.Fab")
			(effects
				(font
					(size 0.7 0.7)
					(thickness 0.15)
				)
				(justify left bottom mirror)
			)
		)
		(fp_text user "Author: Antmicro"
			(at -0.95 -4.169 90)
			(layer "B.Fab")
			(effects
				(font
					(size 0.7 0.7)
					(thickness 0.15)
				)
				(justify left bottom mirror)
			)
		)
		(fp_text user "License: Apache-2.0"
			(at -0.95 -5.169 90)
			(layer "B.Fab")
			(effects
				(font
					(size 0.7 0.7)
					(thickness 0.15)
				)
				(justify left bottom mirror)
			)
		)
		(pad "1" smd roundrect
			(at -0.48 0 270)
			(size 0.59 0.64)
			(layers "B.Cu" "B.Mask" "B.Paste")
			(roundrect_rratio 0.25)
			(net 1108 "Net-(D6-A)")
			(pintype "passive")
		)
		(pad "2" smd roundrect
			(at 0.48 0 270)
			(size 0.59 0.64)
			(layers "B.Cu" "B.Mask" "B.Paste")
			(roundrect_rratio 0.25)
			(net 904 "+20V")
			(pintype "passive")
		)
	)
	(footprint "antmicro-footprints:PCM12SMTR"
		(layer "B.Cu")
		(at 89.505 55.89)
		(property "Reference" "SW2"
			(at -6.665 0.76 0)
			(layer "B.SilkS")
			(effects
				(font
					(size 0.7 0.7)
					(thickness 0.15)
				)
				(justify right top mirror)
			)
		)
		(property "Value" "SW_SPDT_PCM12SMTR"
			(at 0 -4.15 0)
			(layer "B.Fab")
			(effects
				(font
					(size 0.7 0.7)
					(thickness 0.15)
				)
				(justify right top mirror)
			)
		)
		(property "Datasheet" "https://www.mouser.com/datasheet/2/60/pcm-1841544.pdf"
			(at 0 0 0)
			(layer "B.Fab")
			(hide yes)
			(effects
				(font
					(size 1.27 1.27)
					(thickness 0.15)
				)
				(justify mirror)
			)
		)
		(property "Description" "Slide switch"
			(at 0 0 0)
			(layer "B.Fab")
			(hide yes)
			(effects
				(font
					(size 1.27 1.27)
					(thickness 0.15)
				)
				(justify mirror)
			)
		)
		(property "Manufacturer" "C&K"
			(at 0 0 180)
			(unlocked yes)
			(layer "B.Fab")
			(hide yes)
			(effects
				(font
					(size 1 1)
					(thickness 0.15)
				)
				(justify mirror)
			)
		)
		(property "MPN" "PCM12SMTR"
			(at 0 0 180)
			(unlocked yes)
			(layer "B.Fab")
			(hide yes)
			(effects
				(font
					(size 1 1)
					(thickness 0.15)
				)
				(justify mirror)
			)
		)
		(property "Author" "Antmicro"
			(at 0 0 180)
			(unlocked yes)
			(layer "B.Fab")
			(hide yes)
			(effects
				(font
					(size 1 1)
					(thickness 0.15)
				)
				(justify mirror)
			)
		)
		(property "License" "Apache-2.0"
			(at 0 0 180)
			(unlocked yes)
			(layer "B.Fab")
			(hide yes)
			(effects
				(font
					(size 1 1)
					(thickness 0.15)
				)
				(justify mirror)
			)
		)
		(sheetname "/SoM_Power/")
		(sheetfile "som_power.kicad_sch")
		(attr smd)
		(fp_line
			(start -3.351 -0.348)
			(end -3.351 0.251)
			(stroke
				(width 0.15)
				(type solid)
			)
			(layer "B.SilkS")
		)
		(fp_line
			(start -2.901 -1.348)
			(end 2.9 -1.348)
			(stroke
				(width 0.15)
				(type solid)
			)
			(layer "B.SilkS")
		)
		(fp_line
			(start -1.601 1.251)
			(end 0.1 1.251)
			(stroke
				(width 0.15)
				(type solid)
			)
			(layer "B.SilkS")
		)
		(fp_line
			(start 3.349 0.251)
			(end 3.349 -0.348)
			(stroke
				(width 0.15)
				(type solid)
			)
			(layer "B.SilkS")
		)
		(fp_circle
			(center -3.15 2.45)
			(end -3.1 2.39)
			(stroke
				(width 0.15)
				(type solid)
			)
			(fill yes)
			(layer "B.SilkS")
		)
		(fp_line
			(start -4.42 -1.65)
			(end -4.42 1.57)
			(stroke
				(width 0.05)
				(type solid)
			)
			(layer "B.CrtYd")
		)
		(fp_line
			(start -4.42 1.57)
			(end -2.86 1.57)
			(stroke
				(width 0.05)
				(type solid)
			)
			(layer "B.CrtYd")
		)
		(fp_line
			(start -2.86 1.57)
			(end -2.86 2.7)
			(stroke
				(width 0.05)
				(type solid)
			)
			(layer "B.CrtYd")
		)
		(fp_line
			(start -2.86 2.7)
			(end 2.83 2.7)
			(stroke
				(width 0.05)
				(type solid)
			)
			(layer "B.CrtYd")
		)
		(fp_line
			(start -1.77 -3.08)
			(end -1.77 -1.65)
			(stroke
				(width 0.05)
				(type solid)
			)
			(layer "B.CrtYd")
		)
		(fp_line
			(start -1.77 -1.65)
			(end -4.42 -1.65)
			(stroke
				(width 0.05)
				(type solid)
			)
			(layer "B.CrtYd")
		)
		(fp_line
			(start 1.74 -3.08)
			(end -1.77 -3.08)
			(stroke
				(width 0.05)
				(type solid)
			)
			(layer "B.CrtYd")
		)
		(fp_line
			(start 1.74 -1.65)
			(end 1.74 -3.08)
			(stroke
				(width 0.05)
				(type solid)
			)
			(layer "B.CrtYd")
		)
		(fp_line
			(start 2.83 1.57)
			(end 4.4 1.57)
			(stroke
				(width 0.05)
				(type solid)
			)
			(layer "B.CrtYd")
		)
		(fp_line
			(start 2.83 2.7)
			(end 2.83 1.57)
			(stroke
				(width 0.05)
				(type solid)
			)
			(layer "B.CrtYd")
		)
		(fp_line
			(start 4.4 -1.65)
			(end 1.74 -1.65)
			(stroke
				(width 0.05)
				(type solid)
			)
			(layer "B.CrtYd")
		)
		(fp_line
			(start 4.4 1.57)
			(end 4.4 -1.65)
			(stroke
				(width 0.05)
				(type solid)
			)
			(layer "B.CrtYd")
		)
		(fp_line
			(start -3.351 -1.348)
			(end -3.351 1.251)
			(stroke
				(width 0.15)
				(type solid)
			)
			(layer "B.Fab")
		)
		(fp_line
			(start -3.351 1.251)
			(end 3.349 1.251)
			(stroke
				(width 0.15)
				(type solid)
			)
			(layer "B.Fab")
		)
		(fp_line
			(start -1.502 -2.849)
			(end 1.499 -2.849)
			(stroke
				(width 0.15)
				(type solid)
			)
			(layer "B.Fab")
		)
		(fp_line
			(start -1.502 -1.348)
			(end -3.351 -1.348)
			(stroke
				(width 0.15)
				(type solid)
			)
			(layer "B.Fab")
		)
		(fp_line
			(start -1.502 -1.348)
			(end -1.502 -2.849)
			(stroke
				(width 0.15)
				(type solid)
			)
			(layer "B.Fab")
		)
		(fp_line
			(start 1.499 -2.849)
			(end 1.499 -1.348)
			(stroke
				(width 0.15)
				(type solid)
			)
			(layer "B.Fab")
		)
		(fp_line
			(start 1.499 -1.348)
			(end -1.502 -1.348)
			(stroke
				(width 0.15)
				(type solid)
			)
			(layer "B.Fab")
		)
		(fp_line
			(start 3.349 -1.348)
			(end 1.499 -1.348)
			(stroke
				(width 0.15)
				(type solid)
			)
			(layer "B.Fab")
		)
		(fp_line
			(start 3.349 1.251)
			(end 3.349 -1.348)
			(stroke
				(width 0.15)
				(type solid)
			)
			(layer "B.Fab")
		)
		(fp_text user "${REFERENCE}"
			(at -2.152 -7.94 0)
			(layer "B.Fab")
			(effects
				(font
					(size 0.7 0.7)
					(thickness 0.15)
				)
				(justify right top mirror)
			)
		)
		(fp_text user "Author: Antmicro"
			(at -2.152 -9.14 0)
			(layer "B.Fab")
			(effects
				(font
					(size 0.7 0.7)
					(thickness 0.15)
				)
				(justify right top mirror)
			)
		)
		(fp_text user "License: Apache-2.0"
			(at -2.152 -10.339 0)
			(layer "B.Fab")
			(effects
				(font
					(size 0.7 0.7)
					(thickness 0.15)
				)
				(justify right top mirror)
			)
		)
		(pad "" np_thru_hole circle
			(at -1.502 -0.049)
			(size 0.9 0.9)
			(drill 0.9)
			(layers "*.Cu" "*.Mask")
		)
		(pad "" np_thru_hole circle
			(at 1.499 -0.049)
			(size 0.9 0.9)
			(drill 0.9)
			(layers "*.Cu" "*.Mask")
		)
		(pad "1" smd roundrect
			(at -2.25 1.7)
			(size 0.7 1.5)
			(layers "B.Cu" "B.Mask" "B.Paste")
			(roundrect_rratio 0.25)
			(net 1038 "unconnected-(SW2-Pad1)")
			(pintype "passive+no_connect")
		)
		(pad "2" smd roundrect
			(at 0.749 1.7)
			(size 0.7 1.5)
			(layers "B.Cu" "B.Mask" "B.Paste")
			(roundrect_rratio 0.25)
			(net 1037 "Net-(U72-~{MR})")
			(pintype "passive")
		)
		(pad "3" smd roundrect
			(at 2.248 1.7)
			(size 0.7 1.5)
			(layers "B.Cu" "B.Mask" "B.Paste")
			(roundrect_rratio 0.25)
			(net 1036 "Net-(R307-Pad2)")
			(pintype "passive")
		)
		(pad "S1" smd roundrect
			(at -3.651 0.915)
			(size 1 0.8)
			(layers "B.Cu" "B.Mask" "B.Paste")
			(roundrect_rratio 0.25)
			(net 1 "GND")
			(pinfunction "SH")
			(pintype "passive")
		)
		(pad "S2" smd roundrect
			(at -3.651 -1.013)
			(size 1 0.8)
			(layers "B.Cu" "B.Mask" "B.Paste")
			(roundrect_rratio 0.25)
			(net 1 "GND")
			(pinfunction "SH")
			(pintype "passive")
		)
		(pad "S3" smd roundrect
			(at 3.65 -1.013)
			(size 1 0.8)
			(layers "B.Cu" "B.Mask" "B.Paste")
			(roundrect_rratio 0.25)
			(net 1 "GND")
			(pinfunction "SH")
			(pintype "passive")
		)
		(pad "S4" smd roundrect
			(at 3.65 0.915)
			(size 1 0.8)
			(layers "B.Cu" "B.Mask" "B.Paste")
			(roundrect_rratio 0.25)
			(net 1 "GND")
			(pinfunction "SH")
			(pintype "passive")
		)
	)
	(footprint "antmicro-footprints:SOT-523"
		(layer "B.Cu")
		(at 236.4 71 90)
		(property "Reference" "Q2"
			(at -0.8 1.4 90)
			(layer "B.SilkS")
			(effects
				(font
					(size 0.7 0.7)
					(thickness 0.15)
				)
				(justify right top mirror)
			)
		)
		(property "Value" "DMG1012T-7"
			(at 0.1 -1.824 90)
			(layer "B.Fab")
			(effects
				(font
					(size 0.7 0.7)
					(thickness 0.15)
				)
				(justify right top mirror)
			)
		)
		(property "Datasheet" "https://www.diodes.com/assets/Datasheets/ds31783.pdf"
			(at 0 0 90)
			(layer "B.Fab")
			(hide yes)
			(effects
				(font
					(size 1.27 1.27)
					(thickness 0.15)
				)
				(justify mirror)
			)
		)
		(property "Description" "Power MOSFET, N Channel, 20 V, 630 mA, 0.3 ohm, SOT-523, Surface Mount"
			(at 0 0 90)
			(layer "B.Fab")
			(hide yes)
			(effects
				(font
					(size 1.27 1.27)
					(thickness 0.15)
				)
				(justify mirror)
			)
		)
		(property "MPN" "DMG1012T-7"
			(at 0 0 270)
			(unlocked yes)
			(layer "B.Fab")
			(hide yes)
			(effects
				(font
					(size 1 1)
					(thickness 0.15)
				)
				(justify mirror)
			)
		)
		(property "Manufacturer" "Diodes Incorporated"
			(at 0 0 270)
			(unlocked yes)
			(layer "B.Fab")
			(hide yes)
			(effects
				(font
					(size 1 1)
					(thickness 0.15)
				)
				(justify mirror)
			)
		)
		(property "Author" "Antmicro"
			(at 0 0 270)
			(unlocked yes)
			(layer "B.Fab")
			(hide yes)
			(effects
				(font
					(size 1 1)
					(thickness 0.15)
				)
				(justify mirror)
			)
		)
		(property "License" "Apache-2.0"
			(at 0 0 270)
			(unlocked yes)
			(layer "B.Fab")
			(hide yes)
			(effects
				(font
					(size 1 1)
					(thickness 0.15)
				)
				(justify mirror)
			)
		)
		(sheetname "/SoM_Power/")
		(sheetfile "som_power.kicad_sch")
		(attr smd)
		(fp_line
			(start -0.927 0.050999)
			(end -0.927 0.350999)
			(stroke
				(width 0.15)
				(type solid)
			)
			(layer "B.SilkS")
		)
		(fp_line
			(start -0.927 0.350999)
			(end -0.725 0.551)
			(stroke
				(width 0.15)
				(type solid)
			)
			(layer "B.SilkS")
		)
		(fp_line
			(start -0.277 0.551)
			(end -0.277 0.750001)
			(stroke
				(width 0.15)
				(type solid)
			)
			(layer "B.SilkS")
		)
		(fp_line
			(start -0.725 0.551)
			(end -0.277 0.551)
			(stroke
				(width 0.15)
				(type solid)
			)
			(layer "B.SilkS")
		)
		(fp_circle
			(center -0.9652 -0.9652)
			(end -0.915201 -0.9652)
			(stroke
				(width 0.15)
				(type solid)
			)
			(fill yes)
			(layer "B.SilkS")
		)
		(fp_line
			(start -1.12 -1.15)
			(end 1.1 -1.15)
			(stroke
				(width 0.05)
				(type solid)
			)
			(layer "B.CrtYd")
		)
		(fp_line
			(start 1.1 1.159999)
			(end 1.1 -1.15)
			(stroke
				(width 0.05)
				(type solid)
			)
			(layer "B.CrtYd")
		)
		(fp_line
			(start -1.12 1.159999)
			(end -1.12 -1.15)
			(stroke
				(width 0.05)
				(type solid)
			)
			(layer "B.CrtYd")
		)
		(fp_line
			(start -1.12 1.159999)
			(end 1.1 1.159999)
			(stroke
				(width 0.05)
				(type solid)
			)
			(layer "B.CrtYd")
		)
		(fp_line
			(start 0.8 -0.424)
			(end -0.802 -0.424)
			(stroke
				(width 0.15)
				(type solid)
			)
			(layer "B.Fab")
		)
		(fp_line
			(start -0.802 0.276)
			(end -0.802 -0.424)
			(stroke
				(width 0.15)
				(type solid)
			)
			(layer "B.Fab")
		)
		(fp_line
			(start 0.8 0.425)
			(end 0.8 -0.424)
			(stroke
				(width 0.15)
				(type solid)
			)
			(layer "B.Fab")
		)
		(fp_line
			(start 0.8 0.425)
			(end -0.652 0.425)
			(stroke
				(width 0.15)
				(type solid)
			)
			(layer "B.Fab")
		)
		(fp_line
			(start -0.652 0.425)
			(end -0.802 0.276)
			(stroke
				(width 0.15)
				(type solid)
			)
			(layer "B.Fab")
		)
		(fp_circle
			(center -0.9652 -0.9652)
			(end -0.9144 -0.9652)
			(stroke
				(width 0.15)
				(type solid)
			)
			(fill no)
			(layer "B.Fab")
		)
		(fp_text user "License: Apache-2.0"
			(at -1.12 -5.024 90)
			(layer "B.Fab")
			(effects
				(font
					(size 0.7 0.7)
					(thickness 0.15)
				)
				(justify right top mirror)
			)
		)
		(fp_text user "${REFERENCE}"
			(at -1.12 -3.824 90)
			(layer "B.Fab")
			(effects
				(font
					(size 0.7 0.7)
					(thickness 0.15)
				)
				(justify right top mirror)
			)
		)
		(fp_text user "Author: Antmicro"
			(at -1.12 -6.224 90)
			(layer "B.Fab")
			(effects
				(font
					(size 0.7 0.7)
					(thickness 0.15)
				)
				(justify right top mirror)
			)
		)
		(pad "1" smd rect
			(at -0.5 -0.65 90)
			(size 0.4 0.51)
			(layers "B.Cu" "B.Mask" "B.Paste")
			(net 702 "/SoM_Power/~{SYS_RESET}")
			(pinfunction "G")
			(pintype "input")
		)
		(pad "2" smd rect
			(at 0.498 -0.65 90)
			(size 0.4 0.51)
			(layers "B.Cu" "B.Mask" "B.Paste")
			(net 1 "GND")
			(pinfunction "S")
			(pintype "passive")
		)
		(pad "3" smd rect
			(at 0 0.652001 90)
			(size 0.4 0.51)
			(layers "B.Cu" "B.Mask" "B.Paste")
			(net 1393 "Net-(D65-C)")
			(pinfunction "D")
			(pintype "passive")
		)
	)
	(footprint "antmicro-footprints:TP_SMD_0.75mm"
		(layer "B.Cu")
		(at 194.6 80.6815)
		(property "Reference" "TP13"
			(at 0.45 -3.2315 90)
			(layer "B.SilkS")
			(effects
				(font
					(size 0.7 0.7)
					(thickness 0.15)
				)
				(justify left bottom mirror)
			)
		)
		(property "Value" "TP_0.75mm_SMD"
			(at 0 -1.2 180)
			(layer "B.Fab")
			(effects
				(font
					(size 0.7 0.7)
					(thickness 0.15)
				)
				(justify left bottom mirror)
			)
		)
		(property "Description" "SMT test point"
			(at 0 0 180)
			(layer "B.Fab")
			(hide yes)
			(effects
				(font
					(size 1.27 1.27)
					(thickness 0.15)
				)
				(justify mirror)
			)
		)
		(property "MPN" ""
			(at 0 0 180)
			(unlocked yes)
			(layer "B.Fab")
			(hide yes)
			(effects
				(font
					(size 1 1)
					(thickness 0.15)
				)
				(justify mirror)
			)
		)
		(property "Manufacturer" ""
			(at 0 0 180)
			(unlocked yes)
			(layer "B.Fab")
			(hide yes)
			(effects
				(font
					(size 1 1)
					(thickness 0.15)
				)
				(justify mirror)
			)
		)
		(property "Author" "Antmicro"
			(at 0 0 180)
			(unlocked yes)
			(layer "B.Fab")
			(hide yes)
			(effects
				(font
					(size 1 1)
					(thickness 0.15)
				)
				(justify mirror)
			)
		)
		(property "License" "Apache-2.0"
			(at 0 0 180)
			(unlocked yes)
			(layer "B.Fab")
			(hide yes)
			(effects
				(font
					(size 1 1)
					(thickness 0.15)
				)
				(justify mirror)
			)
		)
		(sheetname "/USB Debug, PD/")
		(sheetfile "usb_debug_pd.kicad_sch")
		(attr exclude_from_pos_files exclude_from_bom)
		(fp_circle
			(center 0 0)
			(end 0.475 0)
			(stroke
				(width 0.05)
				(type default)
			)
			(fill no)
			(layer "B.CrtYd")
		)
		(fp_text user "Author: Antmicro"
			(at -0.4 -3.901 180)
			(layer "B.Fab")
			(effects
				(font
					(size 0.7 0.7)
					(thickness 0.15)
				)
				(justify left bottom mirror)
			)
		)
		(fp_text user "License: Apache-2.0"
			(at -0.4 -5.101 180)
			(layer "B.Fab")
			(effects
				(font
					(size 0.7 0.7)
					(thickness 0.15)
				)
				(justify left bottom mirror)
			)
		)
		(fp_text user "${REFERENCE}"
			(at -0.4 -2.7 180)
			(layer "B.Fab")
			(effects
				(font
					(size 0.7 0.7)
					(thickness 0.15)
				)
				(justify left bottom mirror)
			)
		)
		(pad "1" smd circle
			(at 0 0)
			(size 0.75 0.75)
			(layers "B.Cu" "B.Mask")
			(net 1042 "/USB Debug, PD/PDC_I2C2_IRQn")
			(pinfunction "1")
			(pintype "passive")
		)
	)
)
